FILE_TYPE = CONNECTIVITY;
{Allegro Design Entry HDL 17.2-2016 S081 (4005846) 1/11/2022}
"PAGE_NUMBER" = 5;
0"NC";
END.
